FILE_TYPE = CONNECTIVITY;
{Allegro Design Entry HDL 17.2-2016 S081 (4005846) 1/11/2022}
"PAGE_NUMBER" = 172;
0"NC";
1"GND\g";
2"TP_USB2_6_DN";
3"USB2_5_DP";
4"USB2_5_DN";
5"TP_USB2_4_DP";
6"TP_USB2_11_DN";
7"TP_USB2_12_DN";
8"TP_USB2_13_DP";
9"TP_USB2_13_DN";
10"TP_USB2_12_DP";
11"TP_USB2_10_DP"CDS_PHYS_NET_NAME"TP_USB2_10_DP";
12"TP_USB2_10_DN"CDS_PHYS_NET_NAME"TP_USB2_10_DN";
13"TP_USB2_11_DP";
14"TP_USB2_9_DP"CDS_PHYS_NET_NAME"TP_USB2_9_DP";
15"NC_PCH_RSVD<14>";
16"PD_PCH_USB2_COMP";
17"USB2_7_DN";
18"TP_USB2_9_DN"CDS_PHYS_NET_NAME"TP_USB2_9_DN";
19"TP_USB2_6_DP";
20"USB2_8_DP"CDS_PHYS_NET_NAME"TP_USB2_9_DP";
21"USB2_8_DN"CDS_PHYS_NET_NAME"TP_USB2_9_DN";
22"USB2_7_DP";
23"TP_USB2_4_DN";
24"USB2_0_DN";
25"USB2_3_DP";
26"TP_USB2_1_DP";
27"TP_USB2_2_DN";
28"TP_USB2_2_DP";
29"USB2_3_DN";
30"TP_USB2_1_DN";
31"USB2_0_DP";
%"Q_RES"
"2","(-7300,3900)","0","pure_quanta","I10";
;
PART_NUMBER"CS11132FB02"
PACK_TYPE"0402LF"
VALUE"113"
TOLERANCE"1%"
WATTAGE"1/16W"
MATERIAL"CHIP"
$LOCATION"R496"
CDS_LIB"pure_quanta"
CDS_LOCATION"R496"
$SEC"1"
CDS_SEC"1";
"A"
$PN"1"16;
"B"
$PN"2"1;
%"EMMITSBURG_REV0P9"
"2","(-4125,3500)","0","pure_quanta","I11";
;
PART_NUMBER"AJ0QV2N0T00"
MATERIAL"IC"
VALUE"GFNOCPU04302300-QV2N-MM#99A1WT"
PART_TYPE"SMLF"
$LOCATION"U4"
CDS_LIB"pure_quanta"
CDS_LMAN_SYM_OUTLINE"-550,825,550,-825"
NEEDS_NO_SIZE"TRUE"
CDS_LOCATION"U4"
$SEC"2"
CDS_SEC"2";
"USB2_COMP"
$PN"BB41"16;
"USB2P_9"
$PN"AJ41"14;
"USB2P_8"
$PN"AW40"20;
"USB2P_7"
$PN"AK40"22;
"USB2P_6"
$PN"AV41"19;
"USB2P_5"
$PN"AL41"3;
"USB2P_4"
$PN"AU40"5;
"USB2P_3"
$PN"AN40"25;
"USB2P_2"
$PN"AT41"28;
"USB2P_13"
$PN"AG41"8;
"USB2P_12"
$PN"BA40"10;
"USB2P_11"
$PN"AH40"13;
"USB2P_10"
$PN"AY41"11;
"USB2P_1"
$PN"AP41"26;
"USB2P_0"
$PN"AR40"31;
"USB2N_9"
$PN"AJ43"18;
"USB2N_8"
$PN"AW42"21;
"USB2N_7"
$PN"AK42"17;
"USB2N_6"
$PN"AV43"2;
"USB2N_5"
$PN"AL43"4;
"USB2N_4"
$PN"AU42"23;
"USB2N_3"
$PN"AN42"29;
"USB2N_2"
$PN"AT43"27;
"USB2N_13"
$PN"AG43"9;
"USB2N_12"
$PN"BA42"7;
"USB2N_11"
$PN"AH42"6;
"USB2N_10"
$PN"AY43"12;
"USB2N_1"
$PN"AP43"30;
"USB2N_0"
$PN"AR42"24;
"RSVD_BC40"
$PN"BC40"15;
%"UNIVERSAL_GND"
"1","(-7300,3625)","0","logical_power","I9";
;
HDL_POWER"GND"
CDS_LIB"logical_power";
"A"1;
END.
